# T6G (Grand Teton) — schematic netlist excerpt (pin names and nets, part order shuffled) for the footprints in the layout excerpt that follows; sources: Cadence DE-HDL packaged netlist, KiCad conversion of 04192023_DAF0TMB3IC0_F0TG_MB_C_brd_V02_OCP.brd

C2049  Q_CAP  0.1UF 25V 10% X7R  pkg 0402  page 257 : A = P5V_ADC_TIC ; B = GND
R1164  Q_RES  0 5% EMPTY  pkg 0402LF  page 142 : A = P12V_OCP_V3_2_EN_R ; B = P12V_OCP_V3_2_EN_R3

(kicad_pcb
	(version 20260206)
	(generator "pcbnew")
	(generator_version "10.0")
	(general
		(thickness 1.6)
		(legacy_teardrops no)
	)
	(paper "A4")
	(title_block
		(title "04192023_DAF0TMB3IC0_F0TG_MB_C_brd_V02_OCP.brd")
		(comment 1 "Grand Teton / footprints 1360-1361 of 8354")
	)
	(layers
		(0 "F.Cu" signal "TOP")
		(4 "In1.Cu" signal "GND")
		(6 "In2.Cu" signal "IN1")
		(8 "In3.Cu" signal "GND1")
		(10 "In4.Cu" signal "IN2")
		(12 "In5.Cu" signal "GND2")
		(14 "In6.Cu" signal "IN3")
		(16 "In7.Cu" signal "GND3")
		(18 "In8.Cu" signal "VCC")
		(20 "In9.Cu" signal "VCC1")
		(22 "In10.Cu" signal "GND4")
		(24 "In11.Cu" signal "IN4")
		(26 "In12.Cu" signal "GND5")
		(28 "In13.Cu" signal "IN5")
		(30 "In14.Cu" signal "GND6")
		(32 "In15.Cu" signal "IN6")
		(34 "In16.Cu" signal "GND7")
		(2 "B.Cu" signal "BOTTOM")
		(9 "F.Adhes" user "F.Adhesive")
		(11 "B.Adhes" user "B.Adhesive")
		(13 "F.Paste" user "Package Geometry/Pastemask Top")
		(15 "B.Paste" user "Package Geometry/Pastemask Bottom")
		(5 "F.SilkS" user "Ref Des/Silkscreen Top")
		(7 "B.SilkS" user "Ref Des/Silkscreen Bottom")
		(1 "F.Mask" user "Board Geometry/Soldermask Top")
		(3 "B.Mask" user "Board Geometry/Soldermask Bottom")
		(17 "Dwgs.User" user "User.Drawings")
		(19 "Cmts.User" user "User.Comments")
		(21 "Eco1.User" user "User.Eco1")
		(23 "Eco2.User" user "User.Eco2")
		(25 "Edge.Cuts" user "Board Geometry/Outline")
		(27 "Margin" user)
		(31 "F.CrtYd" user "Package Geometry/Place Bound Top")
		(29 "B.CrtYd" user "Package Geometry/Place Bound Bottom")
		(35 "F.Fab" user "Ref Des/Assembly Top")
		(33 "B.Fab" user "Ref Des/Assembly Bottom")
	)
	(footprint ""
		(layer "F.Cu")
		(at 50.072544 -41.99255 180)
		(property "Reference" "R1164"
			(at 0 0 180)
			(layer "F.SilkS")
			(hide yes)
			(effects
				(font
					(size 1.27 1.27)
				)
			)
		)
		(property "Value" ""
			(at 0 0 180)
			(layer "F.Fab")
			(effects
				(font
					(size 1.27 1.27)
				)
			)
		)
		(duplicate_pad_numbers_are_jumpers no)
		(fp_line
			(start 0.7874 0.4064)
			(end -0.7874 0.4064)
			(stroke
				(width 0.1524)
				(type default)
			)
			(layer "F.SilkS")
		)
		(fp_line
			(start 0.7874 -0.4064)
			(end 0.7874 0.4064)
			(stroke
				(width 0.1524)
				(type default)
			)
			(layer "F.SilkS")
		)
		(fp_line
			(start -0.7874 0.4064)
			(end -0.7874 -0.4064)
			(stroke
				(width 0.1524)
				(type default)
			)
			(layer "F.SilkS")
		)
		(fp_line
			(start -0.7874 -0.4064)
			(end 0.7874 -0.4064)
			(stroke
				(width 0.1524)
				(type default)
			)
			(layer "F.SilkS")
		)
		(fp_line
			(start 0.67945 0.3048)
			(end 0.120396 0.3048)
			(stroke
				(width 0.1)
				(type default)
			)
			(layer "F.Fab")
		)
		(fp_line
			(start 0.67945 -0.3048)
			(end 0.67945 0.3048)
			(stroke
				(width 0.1)
				(type default)
			)
			(layer "F.Fab")
		)
		(fp_line
			(start 0.12065 -0.2794)
			(end 0.12065 -0.3048)
			(stroke
				(width 0.1)
				(type default)
			)
			(layer "F.Fab")
		)
		(fp_line
			(start 0.12065 -0.3048)
			(end 0.67945 -0.3048)
			(stroke
				(width 0.1)
				(type default)
			)
			(layer "F.Fab")
		)
		(fp_line
			(start 0.120396 0.3048)
			(end 0.120396 0.2794)
			(stroke
				(width 0.1)
				(type default)
			)
			(layer "F.Fab")
		)
		(fp_line
			(start 0.120396 0.2794)
			(end -0.12065 0.2794)
			(stroke
				(width 0.1)
				(type default)
			)
			(layer "F.Fab")
		)
		(fp_line
			(start -0.12065 0.3048)
			(end -0.67945 0.3048)
			(stroke
				(width 0.1)
				(type default)
			)
			(layer "F.Fab")
		)
		(fp_line
			(start -0.12065 0.2794)
			(end -0.12065 0.3048)
			(stroke
				(width 0.1)
				(type default)
			)
			(layer "F.Fab")
		)
		(fp_line
			(start -0.12065 -0.2794)
			(end 0.12065 -0.2794)
			(stroke
				(width 0.1)
				(type default)
			)
			(layer "F.Fab")
		)
		(fp_line
			(start -0.12065 -0.305054)
			(end -0.12065 -0.2794)
			(stroke
				(width 0.1)
				(type default)
			)
			(layer "F.Fab")
		)
		(fp_line
			(start -0.67945 0.3048)
			(end -0.67945 -0.305054)
			(stroke
				(width 0.1)
				(type default)
			)
			(layer "F.Fab")
		)
		(fp_line
			(start -0.67945 -0.305054)
			(end -0.12065 -0.305054)
			(stroke
				(width 0.1)
				(type default)
			)
			(layer "F.Fab")
		)
		(pad "1" smd circle
			(at -0.40005 0 180)
			(size 0 0)
			(layers "F.Cu" "F.Mask" "F.Paste")
			(net "P12V_OCP_V3_2_EN_R")
		)
		(pad "2" smd circle
			(at 0.40005 0 180)
			(size 0 0)
			(layers "F.Cu" "F.Mask" "F.Paste")
			(net "P12V_OCP_V3_2_EN_R3")
		)
	)
	(footprint ""
		(layer "F.Cu")
		(at 319.940178 -43.700954)
		(property "Reference" "C2049"
			(at 0 0 0)
			(layer "F.SilkS")
			(hide yes)
			(effects
				(font
					(size 1.27 1.27)
				)
			)
		)
		(property "Value" ""
			(at 0 0 0)
			(layer "F.Fab")
			(effects
				(font
					(size 1.27 1.27)
				)
			)
		)
		(duplicate_pad_numbers_are_jumpers no)
		(fp_line
			(start -0.7874 -0.4064)
			(end 0.7874 -0.4064)
			(stroke
				(width 0.1524)
				(type default)
			)
			(layer "F.SilkS")
		)
		(fp_line
			(start -0.7874 0.4064)
			(end -0.7874 -0.4064)
			(stroke
				(width 0.1524)
				(type default)
			)
			(layer "F.SilkS")
		)
		(fp_line
			(start 0.7874 -0.4064)
			(end 0.7874 0.4064)
			(stroke
				(width 0.1524)
				(type default)
			)
			(layer "F.SilkS")
		)
		(fp_line
			(start 0.7874 0.4064)
			(end -0.7874 0.4064)
			(stroke
				(width 0.1524)
				(type default)
			)
			(layer "F.SilkS")
		)
		(fp_line
			(start -0.67945 -0.305054)
			(end -0.12065 -0.305054)
			(stroke
				(width 0.1)
				(type default)
			)
			(layer "F.Fab")
		)
		(fp_line
			(start -0.67945 0.3048)
			(end -0.67945 -0.305054)
			(stroke
				(width 0.1)
				(type default)
			)
			(layer "F.Fab")
		)
		(fp_line
			(start -0.12065 -0.305054)
			(end -0.12065 -0.2794)
			(stroke
				(width 0.1)
				(type default)
			)
			(layer "F.Fab")
		)
		(fp_line
			(start -0.12065 -0.2794)
			(end 0.12065 -0.2794)
			(stroke
				(width 0.1)
				(type default)
			)
			(layer "F.Fab")
		)
		(fp_line
			(start -0.12065 0.2794)
			(end -0.12065 0.3048)
			(stroke
				(width 0.1)
				(type default)
			)
			(layer "F.Fab")
		)
		(fp_line
			(start -0.12065 0.3048)
			(end -0.67945 0.3048)
			(stroke
				(width 0.1)
				(type default)
			)
			(layer "F.Fab")
		)
		(fp_line
			(start 0.120396 0.2794)
			(end -0.12065 0.2794)
			(stroke
				(width 0.1)
				(type default)
			)
			(layer "F.Fab")
		)
		(fp_line
			(start 0.120396 0.3048)
			(end 0.120396 0.2794)
			(stroke
				(width 0.1)
				(type default)
			)
			(layer "F.Fab")
		)
		(fp_line
			(start 0.12065 -0.3048)
			(end 0.67945 -0.3048)
			(stroke
				(width 0.1)
				(type default)
			)
			(layer "F.Fab")
		)
		(fp_line
			(start 0.12065 -0.2794)
			(end 0.12065 -0.3048)
			(stroke
				(width 0.1)
				(type default)
			)
			(layer "F.Fab")
		)
		(fp_line
			(start 0.67945 -0.3048)
			(end 0.67945 0.3048)
			(stroke
				(width 0.1)
				(type default)
			)
			(layer "F.Fab")
		)
		(fp_line
			(start 0.67945 0.3048)
			(end 0.120396 0.3048)
			(stroke
				(width 0.1)
				(type default)
			)
			(layer "F.Fab")
		)
		(pad "1" smd circle
			(at -0.40005 0)
			(size 0 0)
			(layers "F.Cu" "F.Mask" "F.Paste")
			(net "P5V_ADC_TIC")
		)
		(pad "2" smd circle
			(at 0.40005 0)
			(size 0 0)
			(layers "F.Cu" "F.Mask" "F.Paste")
			(net "GND")
		)
	)
)
